# T6G (Grand Teton) — schematic netlist excerpt (pin names and nets, part order shuffled) for the footprints in the layout excerpt that follows; sources: Cadence DE-HDL packaged netlist, KiCad conversion of 04192023_DAF0TMB3IC0_F0TG_MB_C_brd_V02_OCP.brd

PU296  MP5991GLUZ  MP5991GLU-Z IC  pkg LGA32_TH_0-5_5X5  page 264
  VOUT1  = P12V_AUX
  VOUT2  = P12V_AUX
  D_OC  = HSC_D_OC_3
  \on\  = HSC_ON
  GOK  = HSC_FAULT
  FLT_TYPE  = HSC_FLT_TYPE_3
  NC1  = HSC_NC1_3
  MODE  = HSC_MODE_3
  VIN1  = P12V_PSU
  VIN2  = P12V_PSU
  VIN3  = P12V_PSU
  VIN4  = P12V_PSU
  VIN5  = P12V_PSU
  VIN6  = P12V_PSU
  VIN7  = P12V_PSU
  VIN8  = P12V_PSU
  SCREF_OCWREF  = HSC_SCREF_3
  VTEMP  = HSC_VTEMP
  SS  = HSC_SS
  GND  = AGND_HSC
  VDD33  = HSC_VDD_R_3
  IMON  = HSC_IMON
  CS  = HSC_CS_3
  OCREF  = HSC_OCREF
  VOUT3  = P12V_AUX
  VOUT4  = P12V_AUX
  VOUT5  = P12V_AUX
  VOUT6  = P12V_AUX
  VOUT7  = P12V_AUX
  VOUT8  = P12V_AUX
  VOUT9  = P12V_AUX
  VOUT10  = P12V_AUX
  VIN9  = P12V_PSU

(kicad_pcb
	(version 20260206)
	(generator "pcbnew")
	(generator_version "10.0")
	(general
		(thickness 1.6)
		(legacy_teardrops no)
	)
	(paper "A4")
	(title_block
		(title "04192023_DAF0TMB3IC0_F0TG_MB_C_brd_V02_OCP.brd")
		(comment 1 "Grand Teton / footprints 447-447 of 8354")
	)
	(layers
		(0 "F.Cu" signal "TOP")
		(4 "In1.Cu" signal "GND")
		(6 "In2.Cu" signal "IN1")
		(8 "In3.Cu" signal "GND1")
		(10 "In4.Cu" signal "IN2")
		(12 "In5.Cu" signal "GND2")
		(14 "In6.Cu" signal "IN3")
		(16 "In7.Cu" signal "GND3")
		(18 "In8.Cu" signal "VCC")
		(20 "In9.Cu" signal "VCC1")
		(22 "In10.Cu" signal "GND4")
		(24 "In11.Cu" signal "IN4")
		(26 "In12.Cu" signal "GND5")
		(28 "In13.Cu" signal "IN5")
		(30 "In14.Cu" signal "GND6")
		(32 "In15.Cu" signal "IN6")
		(34 "In16.Cu" signal "GND7")
		(2 "B.Cu" signal "BOTTOM")
		(9 "F.Adhes" user "F.Adhesive")
		(11 "B.Adhes" user "B.Adhesive")
		(13 "F.Paste" user "Package Geometry/Pastemask Top")
		(15 "B.Paste" user "Package Geometry/Pastemask Bottom")
		(5 "F.SilkS" user "Ref Des/Silkscreen Top")
		(7 "B.SilkS" user "Ref Des/Silkscreen Bottom")
		(1 "F.Mask" user "Board Geometry/Soldermask Top")
		(3 "B.Mask" user "Board Geometry/Soldermask Bottom")
		(17 "Dwgs.User" user "User.Drawings")
		(19 "Cmts.User" user "User.Comments")
		(21 "Eco1.User" user "User.Eco1")
		(23 "Eco2.User" user "User.Eco2")
		(25 "Edge.Cuts" user "Board Geometry/Outline")
		(27 "Margin" user)
		(31 "F.CrtYd" user "Package Geometry/Place Bound Top")
		(29 "B.CrtYd" user "Package Geometry/Place Bound Bottom")
		(35 "F.Fab" user "Ref Des/Assembly Top")
		(33 "B.Fab" user "Ref Des/Assembly Bottom")
	)
	(footprint ""
		(layer "F.Cu")
		(at 220.872558 -401.920202 180)
		(property "Reference" "PU296"
			(at 2.818384 -5.05206 90)
			(unlocked yes)
			(layer "F.SilkS")
			(effects
				(font
					(size 0.7874 0.5842)
					(thickness 0.1524)
				)
			)
		)
		(property "Value" ""
			(at 0 0 180)
			(layer "F.Fab")
			(effects
				(font
					(size 1.27 1.27)
				)
			)
		)
		(duplicate_pad_numbers_are_jumpers no)
		(fp_line
			(start 2.567686 2.567686)
			(end 2.567686 -2.567686)
			(stroke
				(width 0.1524)
				(type default)
			)
			(layer "F.SilkS")
		)
		(fp_line
			(start 2.567686 -2.567686)
			(end -2.567686 -2.567686)
			(stroke
				(width 0.1524)
				(type default)
			)
			(layer "F.SilkS")
		)
		(fp_line
			(start -2.567686 2.567686)
			(end 2.567686 2.567686)
			(stroke
				(width 0.1524)
				(type default)
			)
			(layer "F.SilkS")
		)
		(fp_line
			(start -2.567686 -2.567686)
			(end -2.567686 2.567686)
			(stroke
				(width 0.1524)
				(type default)
			)
			(layer "F.SilkS")
		)
		(fp_poly
			(pts
				(xy -2.632456 -2.13233) (xy -3.709924 -2.491486) (xy -2.991612 -3.209798)
			)
			(stroke
				(width 0)
				(type default)
			)
			(fill yes)
			(layer "F.SilkS")
		)
		(fp_line
			(start 2.549906 2.549906)
			(end 2.549906 -2.549906)
			(stroke
				(width 0.1)
				(type default)
			)
			(layer "F.Fab")
		)
		(fp_line
			(start 2.549906 -2.549906)
			(end -2.549906 -2.549906)
			(stroke
				(width 0.1)
				(type default)
			)
			(layer "F.Fab")
		)
		(fp_line
			(start -2.549906 2.549906)
			(end 2.549906 2.549906)
			(stroke
				(width 0.1)
				(type default)
			)
			(layer "F.Fab")
		)
		(fp_line
			(start -2.549906 -2.549906)
			(end -2.549906 2.549906)
			(stroke
				(width 0.1)
				(type default)
			)
			(layer "F.Fab")
		)
		(fp_poly
			(pts
				(xy -3.806698 -2.25806) (xy -3.806698 -1.24206) (xy -2.790698 -1.75006)
			)
			(stroke
				(width 0)
				(type default)
			)
			(fill yes)
			(layer "F.Fab")
		)
		(pad "1" smd rect
			(at -2.250186 -1.75006 270)
			(size 0.254 0.3556)
			(layers "F.Cu" "F.Mask" "F.Paste")
			(net "P12V_AUX")
		)
		(pad "2" smd rect
			(at -2.237486 -1.249934 270)
			(size 0.254 0.381)
			(layers "F.Cu" "F.Mask" "F.Paste")
			(net "P12V_AUX")
		)
		(pad "3" smd rect
			(at -2.237486 -0.750062 270)
			(size 0.254 0.381)
			(layers "F.Cu" "F.Mask" "F.Paste")
			(net "HSC_D_OC_3")
		)
		(pad "4" smd rect
			(at -2.237486 -0.249936 270)
			(size 0.254 0.381)
			(layers "F.Cu" "F.Mask" "F.Paste")
			(net "HSC_ON")
		)
		(pad "5" smd rect
			(at -2.237486 0.249936 270)
			(size 0.254 0.381)
			(layers "F.Cu" "F.Mask" "F.Paste")
			(net "HSC_FAULT")
		)
		(pad "6" smd rect
			(at -2.237486 0.750062 270)
			(size 0.254 0.381)
			(layers "F.Cu" "F.Mask" "F.Paste")
			(net "HSC_FLT_TYPE_3")
		)
		(pad "7" smd rect
			(at -2.237486 1.249934 270)
			(size 0.254 0.381)
			(layers "F.Cu" "F.Mask" "F.Paste")
			(net "HSC_NC1_3")
		)
		(pad "8" smd rect
			(at -2.250186 1.75006 270)
			(size 0.254 0.3556)
			(layers "F.Cu" "F.Mask" "F.Paste")
			(net "HSC_MODE_3")
		)
		(pad "9" smd rect
			(at -1.75006 2.250186 180)
			(size 0.254 0.3556)
			(layers "F.Cu" "F.Mask" "F.Paste")
			(net "P12V_PSU")
		)
		(pad "10" smd rect
			(at -1.249934 2.237486 180)
			(size 0.254 0.381)
			(layers "F.Cu" "F.Mask" "F.Paste")
			(net "P12V_PSU")
		)
		(pad "11" smd rect
			(at -0.750062 2.237486 180)
			(size 0.254 0.381)
			(layers "F.Cu" "F.Mask" "F.Paste")
			(net "P12V_PSU")
		)
		(pad "12" smd rect
			(at -0.249936 2.237486 180)
			(size 0.254 0.381)
			(layers "F.Cu" "F.Mask" "F.Paste")
			(net "P12V_PSU")
		)
		(pad "13" smd rect
			(at 0.249936 2.237486 180)
			(size 0.254 0.381)
			(layers "F.Cu" "F.Mask" "F.Paste")
			(net "P12V_PSU")
		)
		(pad "14" smd rect
			(at 0.750062 2.237486 180)
			(size 0.254 0.381)
			(layers "F.Cu" "F.Mask" "F.Paste")
			(net "P12V_PSU")
		)
		(pad "15" smd rect
			(at 1.249934 2.237486 180)
			(size 0.254 0.381)
			(layers "F.Cu" "F.Mask" "F.Paste")
			(net "P12V_PSU")
		)
		(pad "16" smd rect
			(at 1.75006 2.250186 180)
			(size 0.254 0.3556)
			(layers "F.Cu" "F.Mask" "F.Paste")
			(net "P12V_PSU")
		)
		(pad "17" smd rect
			(at 2.250186 1.75006 270)
			(size 0.254 0.3556)
			(layers "F.Cu" "F.Mask" "F.Paste")
			(net "HSC_SCREF_3")
		)
		(pad "18" smd rect
			(at 2.237486 1.249934 270)
			(size 0.254 0.381)
			(layers "F.Cu" "F.Mask" "F.Paste")
			(net "HSC_VTEMP")
		)
		(pad "19" smd rect
			(at 2.237486 0.750062 270)
			(size 0.254 0.381)
			(layers "F.Cu" "F.Mask" "F.Paste")
			(net "HSC_SS")
		)
		(pad "20" smd rect
			(at 2.237486 0.249936 270)
			(size 0.254 0.381)
			(layers "F.Cu" "F.Mask" "F.Paste")
			(net "AGND_HSC")
		)
		(pad "21" smd rect
			(at 2.237486 -0.249936 270)
			(size 0.254 0.381)
			(layers "F.Cu" "F.Mask" "F.Paste")
			(net "HSC_VDD_R_3")
		)
		(pad "22" smd rect
			(at 2.237486 -0.750062 270)
			(size 0.254 0.381)
			(layers "F.Cu" "F.Mask" "F.Paste")
			(net "HSC_IMON")
		)
		(pad "23" smd rect
			(at 2.237486 -1.249934 270)
			(size 0.254 0.381)
			(layers "F.Cu" "F.Mask" "F.Paste")
			(net "HSC_CS_3")
		)
		(pad "24" smd rect
			(at 2.250186 -1.75006 270)
			(size 0.254 0.3556)
			(layers "F.Cu" "F.Mask" "F.Paste")
			(net "HSC_OCREF")
		)
		(pad "25" smd rect
			(at 1.75006 -2.250186 180)
			(size 0.254 0.3556)
			(layers "F.Cu" "F.Mask" "F.Paste")
			(net "P12V_AUX")
		)
		(pad "26" smd rect
			(at 1.249934 -2.237486 180)
			(size 0.254 0.381)
			(layers "F.Cu" "F.Mask" "F.Paste")
			(net "P12V_AUX")
		)
		(pad "27" smd rect
			(at 0.750062 -2.237486 180)
			(size 0.254 0.381)
			(layers "F.Cu" "F.Mask" "F.Paste")
			(net "P12V_AUX")
		)
		(pad "28" smd rect
			(at 0.249936 -2.237486 180)
			(size 0.254 0.381)
			(layers "F.Cu" "F.Mask" "F.Paste")
			(net "P12V_AUX")
		)
		(pad "29" smd rect
			(at -0.249936 -2.237486 180)
			(size 0.254 0.381)
			(layers "F.Cu" "F.Mask" "F.Paste")
			(net "P12V_AUX")
		)
		(pad "30" smd rect
			(at -0.750062 -2.237486 180)
			(size 0.254 0.381)
			(layers "F.Cu" "F.Mask" "F.Paste")
			(net "P12V_AUX")
		)
		(pad "31" smd rect
			(at -1.249934 -2.237486 180)
			(size 0.254 0.381)
			(layers "F.Cu" "F.Mask" "F.Paste")
			(net "P12V_AUX")
		)
		(pad "32" smd rect
			(at -1.75006 -2.250186 180)
			(size 0.254 0.3556)
			(layers "F.Cu" "F.Mask" "F.Paste")
			(net "P12V_AUX")
		)
		(pad "33" smd rect
			(at 0 0 180)
			(size 3.4036 3.4036)
			(layers "F.Cu" "F.Mask" "F.Paste")
			(net "P12V_PSU")
		)
		(zone
			(layer "F.Cu")
			(hatch none 0.5)
			(connect_pads
				(clearance 0)
			)
			(min_thickness 0.25)
			(keepout
				(tracks not_allowed)
				(vias allowed)
				(pads allowed)
				(copperpour not_allowed)
				(footprints allowed)
			)
			(placement
				(enabled no)
				(sheetname "")
			)
			(fill
				(thermal_gap 0.5)
				(thermal_bridge_width 0.5)
				(island_removal_mode 0)
			)
			(polygon
				(pts
					(xy 218.850972 -403.5806) (xy 219.119958 -403.5806) (xy 219.119958 -400.167602) (xy 222.625158 -400.167602)
					(xy 222.625158 -402.428202) (xy 222.868744 -402.428202) (xy 222.868744 -400.472402) (xy 222.894144 -400.472402)
					(xy 222.894144 -399.898616) (xy 222.320358 -399.898616) (xy 222.320358 -399.924016) (xy 219.424758 -399.924016)
					(xy 219.424758 -399.898616) (xy 218.850972 -399.898616) (xy 218.850972 -400.472402) (xy 218.876372 -400.472402)
					(xy 218.876372 -403.368002) (xy 218.850972 -403.368002)
				)
			)
		)
	)
)
